(kicad_pcb
	(version 20260206)
	(generator "pcbnew")
	(generator_version "10.0")
	(general
		(thickness 1.6)
		(legacy_teardrops no)
	)
	(paper "A4")
	(title_block
		(title "04192023_DAF0TMB3IC0_F0TG_MB_C_brd_V02_OCP.brd")
		(comment 1 "Grand Teton / footprints 3042-3046 of 8354")
	)
	(layers
		(0 "F.Cu" signal "TOP")
		(4 "In1.Cu" signal "GND")
		(6 "In2.Cu" signal "IN1")
		(8 "In3.Cu" signal "GND1")
		(10 "In4.Cu" signal "IN2")
		(12 "In5.Cu" signal "GND2")
		(14 "In6.Cu" signal "IN3")
		(16 "In7.Cu" signal "GND3")
		(18 "In8.Cu" signal "VCC")
		(20 "In9.Cu" signal "VCC1")
		(22 "In10.Cu" signal "GND4")
		(24 "In11.Cu" signal "IN4")
		(26 "In12.Cu" signal "GND5")
		(28 "In13.Cu" signal "IN5")
		(30 "In14.Cu" signal "GND6")
		(32 "In15.Cu" signal "IN6")
		(34 "In16.Cu" signal "GND7")
		(2 "B.Cu" signal "BOTTOM")
		(9 "F.Adhes" user "F.Adhesive")
		(11 "B.Adhes" user "B.Adhesive")
		(13 "F.Paste" user "Package Geometry/Pastemask Top")
		(15 "B.Paste" user "Package Geometry/Pastemask Bottom")
		(5 "F.SilkS" user "Ref Des/Silkscreen Top")
		(7 "B.SilkS" user "Ref Des/Silkscreen Bottom")
		(1 "F.Mask" user "Board Geometry/Soldermask Top")
		(3 "B.Mask" user "Board Geometry/Soldermask Bottom")
		(17 "Dwgs.User" user "User.Drawings")
		(19 "Cmts.User" user "User.Comments")
		(21 "Eco1.User" user "User.Eco1")
		(23 "Eco2.User" user "User.Eco2")
		(25 "Edge.Cuts" user "Board Geometry/Outline")
		(27 "Margin" user)
		(31 "F.CrtYd" user "Package Geometry/Place Bound Top")
		(29 "B.CrtYd" user "Package Geometry/Place Bound Bottom")
		(35 "F.Fab" user "Ref Des/Assembly Top")
		(33 "B.Fab" user "Ref Des/Assembly Bottom")
	)
	(footprint ""
		(layer "F.Cu")
		(at 188.849 -96.103948 -90)
		(property "Reference" "R1303"
			(at 0 0 270)
			(layer "F.SilkS")
			(hide yes)
			(effects
				(font
					(size 1.27 1.27)
				)
			)
		)
		(property "Value" ""
			(at 0 0 270)
			(layer "F.Fab")
			(effects
				(font
					(size 1.27 1.27)
				)
			)
		)
		(duplicate_pad_numbers_are_jumpers no)
		(fp_line
			(start -0.7874 0.4064)
			(end -0.7874 -0.4064)
			(stroke
				(width 0.1524)
				(type default)
			)
			(layer "F.SilkS")
		)
		(fp_line
			(start 0.7874 0.4064)
			(end -0.7874 0.4064)
			(stroke
				(width 0.1524)
				(type default)
			)
			(layer "F.SilkS")
		)
		(fp_line
			(start -0.7874 -0.4064)
			(end 0.7874 -0.4064)
			(stroke
				(width 0.1524)
				(type default)
			)
			(layer "F.SilkS")
		)
		(fp_line
			(start 0.7874 -0.4064)
			(end 0.7874 0.4064)
			(stroke
				(width 0.1524)
				(type default)
			)
			(layer "F.SilkS")
		)
		(fp_line
			(start -0.67945 0.3048)
			(end -0.67945 -0.305054)
			(stroke
				(width 0.1)
				(type default)
			)
			(layer "F.Fab")
		)
		(fp_line
			(start -0.12065 0.3048)
			(end -0.67945 0.3048)
			(stroke
				(width 0.1)
				(type default)
			)
			(layer "F.Fab")
		)
		(fp_line
			(start 0.120396 0.3048)
			(end 0.120396 0.2794)
			(stroke
				(width 0.1)
				(type default)
			)
			(layer "F.Fab")
		)
		(fp_line
			(start 0.67945 0.3048)
			(end 0.120396 0.3048)
			(stroke
				(width 0.1)
				(type default)
			)
			(layer "F.Fab")
		)
		(fp_line
			(start -0.12065 0.2794)
			(end -0.12065 0.3048)
			(stroke
				(width 0.1)
				(type default)
			)
			(layer "F.Fab")
		)
		(fp_line
			(start 0.120396 0.2794)
			(end -0.12065 0.2794)
			(stroke
				(width 0.1)
				(type default)
			)
			(layer "F.Fab")
		)
		(fp_line
			(start -0.12065 -0.2794)
			(end 0.12065 -0.2794)
			(stroke
				(width 0.1)
				(type default)
			)
			(layer "F.Fab")
		)
		(fp_line
			(start 0.12065 -0.2794)
			(end 0.12065 -0.3048)
			(stroke
				(width 0.1)
				(type default)
			)
			(layer "F.Fab")
		)
		(fp_line
			(start 0.12065 -0.3048)
			(end 0.67945 -0.3048)
			(stroke
				(width 0.1)
				(type default)
			)
			(layer "F.Fab")
		)
		(fp_line
			(start 0.67945 -0.3048)
			(end 0.67945 0.3048)
			(stroke
				(width 0.1)
				(type default)
			)
			(layer "F.Fab")
		)
		(fp_line
			(start -0.67945 -0.305054)
			(end -0.12065 -0.305054)
			(stroke
				(width 0.1)
				(type default)
			)
			(layer "F.Fab")
		)
		(fp_line
			(start -0.12065 -0.305054)
			(end -0.12065 -0.2794)
			(stroke
				(width 0.1)
				(type default)
			)
			(layer "F.Fab")
		)
		(pad "1" smd circle
			(at -0.40005 0 270)
			(size 0 0)
			(layers "F.Cu" "F.Mask" "F.Paste")
			(net "FM_SMB_RST_E1S_0_N")
		)
		(pad "2" smd circle
			(at 0.40005 0 270)
			(size 0 0)
			(layers "F.Cu" "F.Mask" "F.Paste")
			(net "P3V3_AUX")
		)
	)
	(footprint ""
		(layer "F.Cu")
		(at 456.50023 -51.066954 180)
		(property "Reference" "PU9"
			(at -4.50596 2.89306 0)
			(unlocked yes)
			(layer "F.SilkS")
			(effects
				(font
					(size 0.7874 0.5842)
					(thickness 0.1524)
				)
				(justify left)
			)
		)
		(property "Value" ""
			(at 0 0 180)
			(layer "F.Fab")
			(effects
				(font
					(size 1.27 1.27)
				)
			)
		)
		(duplicate_pad_numbers_are_jumpers no)
		(fp_line
			(start 2.549906 3.050032)
			(end 2.549906 2.577846)
			(stroke
				(width 0.1524)
				(type default)
			)
			(layer "F.SilkS")
		)
		(fp_line
			(start 2.549906 -2.51968)
			(end 2.549906 -3.050032)
			(stroke
				(width 0.1524)
				(type default)
			)
			(layer "F.SilkS")
		)
		(fp_line
			(start 2.549906 -3.050032)
			(end 2.032 -3.050032)
			(stroke
				(width 0.1524)
				(type default)
			)
			(layer "F.SilkS")
		)
		(fp_line
			(start 2.13487 3.050032)
			(end 2.549906 3.050032)
			(stroke
				(width 0.1524)
				(type default)
			)
			(layer "F.SilkS")
		)
		(fp_line
			(start -2.032 -3.050032)
			(end -2.549906 -3.050032)
			(stroke
				(width 0.1524)
				(type default)
			)
			(layer "F.SilkS")
		)
		(fp_line
			(start -2.549906 3.050032)
			(end -2.08153 3.050032)
			(stroke
				(width 0.1524)
				(type default)
			)
			(layer "F.SilkS")
		)
		(fp_line
			(start -2.549906 2.577846)
			(end -2.549906 3.050032)
			(stroke
				(width 0.1524)
				(type default)
			)
			(layer "F.SilkS")
		)
		(fp_line
			(start -2.549906 -3.050032)
			(end -2.549906 -2.51968)
			(stroke
				(width 0.1524)
				(type default)
			)
			(layer "F.SilkS")
		)
		(fp_poly
			(pts
				(xy -2.72796 -2.277872) (xy -3.04673 -2.118614) (xy -3.04673 -2.43713)
			)
			(stroke
				(width 0)
				(type default)
			)
			(fill yes)
			(layer "F.SilkS")
		)
		(fp_line
			(start 2.549906 3.050032)
			(end 2.549906 -3.050032)
			(stroke
				(width 0.1)
				(type default)
			)
			(layer "F.Fab")
		)
		(fp_line
			(start 2.549906 -3.050032)
			(end -2.549906 -3.050032)
			(stroke
				(width 0.1)
				(type default)
			)
			(layer "F.Fab")
		)
		(fp_line
			(start -2.549906 3.050032)
			(end 2.549906 3.050032)
			(stroke
				(width 0.1)
				(type default)
			)
			(layer "F.Fab")
		)
		(fp_line
			(start -2.549906 -3.050032)
			(end -2.549906 3.050032)
			(stroke
				(width 0.1)
				(type default)
			)
			(layer "F.Fab")
		)
		(fp_poly
			(pts
				(xy -3.8354 -2.757932) (xy -3.8354 -1.741932) (xy -2.8194 -2.249932)
			)
			(stroke
				(width 0)
				(type default)
			)
			(fill yes)
			(layer "F.Fab")
		)
		(pad "1" smd rect
			(at -2.362708 -2.249932 270)
			(size 0.2794 0.5842)
			(layers "F.Cu" "F.Mask" "F.Paste")
			(net "P3V3_AUX_ILIM")
		)
		(pad "2" smd rect
			(at -2.350008 -1.75006 270)
			(size 0.2794 0.6096)
			(layers "F.Cu" "F.Mask" "F.Paste")
			(net "PWRGD_P3V3_AUX_R1")
		)
		(pad "3" smd rect
			(at -2.350008 -1.249934 270)
			(size 0.2794 0.6096)
			(layers "F.Cu" "F.Mask" "F.Paste")
			(net "P12V_AUX")
		)
		(pad "4" smd rect
			(at -2.350008 -0.750062 270)
			(size 0.2794 0.6096)
			(layers "F.Cu" "F.Mask" "F.Paste")
			(net "P3V3_AUX_VCC")
		)
		(pad "5" smd rect
			(at -2.350008 -0.249936 270)
			(size 0.2794 0.6096)
			(layers "F.Cu" "F.Mask" "F.Paste")
			(net "P3V3_AUX_VDRV")
		)
		(pad "6" smd rect
			(at -2.350008 0.249936 270)
			(size 0.2794 0.6096)
			(layers "F.Cu" "F.Mask" "F.Paste")
			(net "NC_PU9_3")
		)
		(pad "7_10-19" smd circle
			(at 0 0.062484 90)
			(size 0 0)
			(layers "F.Cu" "F.Mask" "F.Paste")
			(net "GND")
		)
		(pad "11_18" smd circle
			(at 0 2.712466 90)
			(size 0 0)
			(layers "F.Cu" "F.Mask" "F.Paste")
			(net "SW_P3V3_AUX_SW")
		)
		(pad "20_24" smd circle
			(at 1.787906 0.749808 180)
			(size 0 0)
			(layers "F.Cu" "F.Mask" "F.Paste")
			(net "SW_P3V3_AUX_FLT")
		)
		(pad "25" smd rect
			(at 2.350008 -0.750062 270)
			(size 0.2794 0.6096)
			(layers "F.Cu" "F.Mask" "F.Paste")
			(net "SW_P3V3_AUX_BOOTR")
		)
		(pad "26" smd rect
			(at 2.350008 -1.249934 270)
			(size 0.2794 0.6096)
			(layers "F.Cu" "F.Mask" "F.Paste")
			(net "SW_P3V3_AUX_BOOT")
		)
		(pad "27" smd rect
			(at 2.350008 -1.75006 270)
			(size 0.2794 0.6096)
			(layers "F.Cu" "F.Mask" "F.Paste")
			(net "P3V3_AUX_EN")
		)
		(pad "28" smd rect
			(at 2.362708 -2.249932 270)
			(size 0.2794 0.5842)
			(layers "F.Cu" "F.Mask" "F.Paste")
			(net "P3V3_AUX_VOS")
		)
		(pad "29" smd rect
			(at 1.75006 -2.887726 180)
			(size 0.2794 0.5842)
			(layers "F.Cu" "F.Mask" "F.Paste")
			(net "P3V3_AUX_SS")
		)
		(pad "30" smd rect
			(at 1.249934 -2.875026 180)
			(size 0.2794 0.6096)
			(layers "F.Cu" "F.Mask" "F.Paste")
			(net "P3V3_AUX_FB")
		)
		(pad "31" smd rect
			(at 0.750062 -2.875026 180)
			(size 0.2794 0.6096)
			(layers "F.Cu" "F.Mask" "F.Paste")
			(net "GND")
		)
		(pad "32" smd rect
			(at 0.249936 -2.875026 180)
			(size 0.2794 0.6096)
			(layers "F.Cu" "F.Mask" "F.Paste")
			(net "GND")
		)
		(pad "33" smd rect
			(at -0.249936 -2.875026 180)
			(size 0.2794 0.6096)
			(layers "F.Cu" "F.Mask" "F.Paste")
			(net "NC_PU9_1")
		)
		(pad "34" smd rect
			(at -0.750062 -2.875026 180)
			(size 0.2794 0.6096)
			(layers "F.Cu" "F.Mask" "F.Paste")
			(net "NC_PU9_2")
		)
		(pad "35" smd rect
			(at -1.249934 -2.875026 180)
			(size 0.2794 0.6096)
			(layers "F.Cu" "F.Mask" "F.Paste")
			(net "NC_HICCUP")
		)
		(pad "36" smd rect
			(at -1.75006 -2.887726 180)
			(size 0.2794 0.5842)
			(layers "F.Cu" "F.Mask" "F.Paste")
			(net "P3V3_AUX_MODE")
		)
		(pad "37" smd rect
			(at -1.549908 0.150114 270)
			(size 0.3048 0.508)
			(layers "F.Cu" "F.Mask" "F.Paste")
			(net "NC_PU9_4")
		)
		(zone
			(layer "F.Cu")
			(hatch none 0.5)
			(connect_pads
				(clearance 0)
			)
			(min_thickness 0.25)
			(keepout
				(tracks not_allowed)
				(vias allowed)
				(pads allowed)
				(copperpour not_allowed)
				(footprints allowed)
			)
			(placement
				(enabled no)
				(sheetname "")
			)
			(fill
				(thermal_gap 0.5)
				(thermal_bridge_width 0.5)
				(island_removal_mode 0)
			)
			(polygon
				(pts
					(xy 459.04023 -53.467) (xy 458.589888 -53.467) (xy 458.554836 -53.431948) (xy 454.445624 -53.431948)
					(xy 454.410572 -53.467) (xy 453.96023 -53.467) (xy 453.96023 -53.642006) (xy 459.04023 -53.642006)
				)
			)
		)
		(zone
			(layer "F.Cu")
			(hatch none 0.5)
			(connect_pads
				(clearance 0)
			)
			(min_thickness 0.25)
			(keepout
				(tracks not_allowed)
				(vias allowed)
				(pads allowed)
				(copperpour not_allowed)
				(footprints allowed)
			)
			(placement
				(enabled no)
				(sheetname "")
			)
			(fill
				(thermal_gap 0.5)
				(thermal_bridge_width 0.5)
				(island_removal_mode 0)
			)
			(polygon
				(pts
					(xy 458.494638 -51.093624) (xy 458.354938 -51.093624) (xy 458.354938 -51.420522) (xy 457.745338 -51.420522)
					(xy 457.745338 -51.013868) (xy 458.354938 -51.013868) (xy 458.354938 -51.068224) (xy 458.494638 -51.068224)
					(xy 458.494638 -49.111154) (xy 458.520038 -49.111154) (xy 458.520038 -48.522128) (xy 457.94803 -48.522128)
					(xy 457.94803 -48.547528) (xy 455.05243 -48.547528) (xy 455.05243 -48.522128) (xy 454.480422 -48.522128)
					(xy 454.480422 -49.111154) (xy 454.505822 -49.111154) (xy 454.505822 -50.735992) (xy 455.5744 -50.735992)
					(xy 455.5744 -52.932076) (xy 454.44537 -52.932076) (xy 454.410572 -52.966874) (xy 453.96023 -52.966874)
					(xy 453.96023 -53.167026) (xy 454.389744 -53.167026) (xy 454.424796 -53.131974) (xy 455.874374 -53.131974)
					(xy 455.874374 -50.467006) (xy 454.725278 -50.467006) (xy 454.725278 -48.791876) (xy 458.275182 -48.791876)
					(xy 458.275182 -50.76698) (xy 457.52512 -50.76698) (xy 457.52512 -51.666902) (xy 458.494638 -51.666902)
				)
			)
		)
	)
	(footprint ""
		(layer "F.Cu")
		(at 124.840238 -42.57675 180)
		(property "Reference" "R6277"
			(at 0 0 180)
			(layer "F.SilkS")
			(hide yes)
			(effects
				(font
					(size 1.27 1.27)
				)
			)
		)
		(property "Value" ""
			(at 0 0 180)
			(layer "F.Fab")
			(effects
				(font
					(size 1.27 1.27)
				)
			)
		)
		(duplicate_pad_numbers_are_jumpers no)
		(fp_line
			(start 0.7874 0.4064)
			(end -0.7874 0.4064)
			(stroke
				(width 0.1524)
				(type default)
			)
			(layer "F.SilkS")
		)
		(fp_line
			(start 0.7874 -0.4064)
			(end 0.7874 0.4064)
			(stroke
				(width 0.1524)
				(type default)
			)
			(layer "F.SilkS")
		)
		(fp_line
			(start -0.7874 0.4064)
			(end -0.7874 -0.4064)
			(stroke
				(width 0.1524)
				(type default)
			)
			(layer "F.SilkS")
		)
		(fp_line
			(start -0.7874 -0.4064)
			(end 0.7874 -0.4064)
			(stroke
				(width 0.1524)
				(type default)
			)
			(layer "F.SilkS")
		)
		(fp_line
			(start 0.67945 0.3048)
			(end 0.120396 0.3048)
			(stroke
				(width 0.1)
				(type default)
			)
			(layer "F.Fab")
		)
		(fp_line
			(start 0.67945 -0.3048)
			(end 0.67945 0.3048)
			(stroke
				(width 0.1)
				(type default)
			)
			(layer "F.Fab")
		)
		(fp_line
			(start 0.12065 -0.2794)
			(end 0.12065 -0.3048)
			(stroke
				(width 0.1)
				(type default)
			)
			(layer "F.Fab")
		)
		(fp_line
			(start 0.12065 -0.3048)
			(end 0.67945 -0.3048)
			(stroke
				(width 0.1)
				(type default)
			)
			(layer "F.Fab")
		)
		(fp_line
			(start 0.120396 0.3048)
			(end 0.120396 0.2794)
			(stroke
				(width 0.1)
				(type default)
			)
			(layer "F.Fab")
		)
		(fp_line
			(start 0.120396 0.2794)
			(end -0.12065 0.2794)
			(stroke
				(width 0.1)
				(type default)
			)
			(layer "F.Fab")
		)
		(fp_line
			(start -0.12065 0.3048)
			(end -0.67945 0.3048)
			(stroke
				(width 0.1)
				(type default)
			)
			(layer "F.Fab")
		)
		(fp_line
			(start -0.12065 0.2794)
			(end -0.12065 0.3048)
			(stroke
				(width 0.1)
				(type default)
			)
			(layer "F.Fab")
		)
		(fp_line
			(start -0.12065 -0.2794)
			(end 0.12065 -0.2794)
			(stroke
				(width 0.1)
				(type default)
			)
			(layer "F.Fab")
		)
		(fp_line
			(start -0.12065 -0.305054)
			(end -0.12065 -0.2794)
			(stroke
				(width 0.1)
				(type default)
			)
			(layer "F.Fab")
		)
		(fp_line
			(start -0.67945 0.3048)
			(end -0.67945 -0.305054)
			(stroke
				(width 0.1)
				(type default)
			)
			(layer "F.Fab")
		)
		(fp_line
			(start -0.67945 -0.305054)
			(end -0.12065 -0.305054)
			(stroke
				(width 0.1)
				(type default)
			)
			(layer "F.Fab")
		)
		(pad "1" smd circle
			(at -0.40005 0 180)
			(size 0 0)
			(layers "F.Cu" "F.Mask" "F.Paste")
			(net "P3V3_AUX")
		)
		(pad "2" smd circle
			(at 0.40005 0 180)
			(size 0 0)
			(layers "F.Cu" "F.Mask" "F.Paste")
			(net "USB_HUB2_MRP_PRT_CTL4_GANGPWR")
		)
	)
	(footprint ""
		(layer "F.Cu")
		(at 35.066478 -17.623536 90)
		(property "Reference" "C692"
			(at 0 0 90)
			(layer "F.SilkS")
			(hide yes)
			(effects
				(font
					(size 1.27 1.27)
				)
			)
		)
		(property "Value" ""
			(at 0 0 90)
			(layer "F.Fab")
			(effects
				(font
					(size 1.27 1.27)
				)
			)
		)
		(duplicate_pad_numbers_are_jumpers no)
		(fp_line
			(start 0.299974 -0.150114)
			(end 0.299974 0.150114)
			(stroke
				(width 0.1)
				(type default)
			)
			(layer "F.Fab")
		)
		(fp_line
			(start -0.299974 -0.150114)
			(end 0.299974 -0.150114)
			(stroke
				(width 0.1)
				(type default)
			)
			(layer "F.Fab")
		)
		(fp_line
			(start 0.299974 0.150114)
			(end -0.299974 0.150114)
			(stroke
				(width 0.1)
				(type default)
			)
			(layer "F.Fab")
		)
		(fp_line
			(start -0.299974 0.150114)
			(end -0.299974 -0.150114)
			(stroke
				(width 0.1)
				(type default)
			)
			(layer "F.Fab")
		)
		(pad "1" smd rect
			(at -0.2667 0 90)
			(size 0.3048 0.381)
			(layers "F.Cu" "F.Mask" "F.Paste")
			(net "P5E_CPU1_G1_TX_C_DN<8>")
		)
		(pad "2" smd rect
			(at 0.2667 0 90)
			(size 0.3048 0.381)
			(layers "F.Cu" "F.Mask" "F.Paste")
			(net "P5E_CPU1_G1_TX_DN<8>")
		)
	)
	(footprint ""
		(layer "F.Cu")
		(at 365.7854 -426.604176)
		(property "Reference" "R1420"
			(at 0 0 0)
			(layer "F.SilkS")
			(hide yes)
			(effects
				(font
					(size 1.27 1.27)
				)
			)
		)
		(property "Value" ""
			(at 0 0 0)
			(layer "F.Fab")
			(effects
				(font
					(size 1.27 1.27)
				)
			)
		)
		(duplicate_pad_numbers_are_jumpers no)
		(fp_line
			(start -0.32512 -0.175006)
			(end 0.32512 -0.175006)
			(stroke
				(width 0.1)
				(type default)
			)
			(layer "F.Fab")
		)
		(fp_line
			(start -0.32512 0.175006)
			(end -0.32512 -0.175006)
			(stroke
				(width 0.1)
				(type default)
			)
			(layer "F.Fab")
		)
		(fp_line
			(start 0.32512 -0.175006)
			(end 0.32512 0.175006)
			(stroke
				(width 0.1)
				(type default)
			)
			(layer "F.Fab")
		)
		(fp_line
			(start 0.32512 0.175006)
			(end -0.32512 0.175006)
			(stroke
				(width 0.1)
				(type default)
			)
			(layer "F.Fab")
		)
		(pad "1" smd rect
			(at -0.2667 0)
			(size 0.3048 0.381)
			(layers "F.Cu" "F.Mask" "F.Paste")
			(net "P1V8_CPU0_RT_1D")
		)
		(pad "2" smd rect
			(at 0.2667 0 180)
			(size 0.3048 0.381)
			(layers "F.Cu" "F.Mask" "F.Paste")
			(net "SMB_RT_CPU0_P3_ROM_MUX_1D_SDA")
		)
	)
)
